# S9S_MB_2U (Grand Teton) — schematic netlist excerpt (pin names and nets, part order shuffled) for the footprints in the layout excerpt that follows; sources: Cadence DE-HDL packaged netlist, KiCad conversion of 03242023_DA0F0TMBIJ0_F0T_Motherboard_J_brd_V01_OCP.brd

C405  Q_CAP  22UF 4V 20% X6S  pkg C0402  page 74 : A = PVCCD_HV_CPU0 ; B = GND
R4464  Q_RES  100K 1% EMPTY  pkg 0402LF  page 196 : A = USB_HUB_2_PGANG ; B = GND

(kicad_pcb
	(version 20260206)
	(generator "pcbnew")
	(generator_version "10.0")
	(general
		(thickness 1.6)
		(legacy_teardrops no)
	)
	(paper "A4")
	(title_block
		(title "03242023_DA0F0TMBIJ0_F0T_Motherboard_J_brd_V01_OCP.brd")
		(comment 1 "Grand Teton / footprints 1879-1880 of 6105")
	)
	(layers
		(0 "F.Cu" signal "TOP")
		(4 "In1.Cu" signal "GND")
		(6 "In2.Cu" signal "IN1")
		(8 "In3.Cu" signal "GND1")
		(10 "In4.Cu" signal "IN2")
		(12 "In5.Cu" signal "GND2")
		(14 "In6.Cu" signal "IN3")
		(16 "In7.Cu" signal "GND3")
		(18 "In8.Cu" signal "VCC")
		(20 "In9.Cu" signal "VCC1")
		(22 "In10.Cu" signal "GND4")
		(24 "In11.Cu" signal "IN4")
		(26 "In12.Cu" signal "GND5")
		(28 "In13.Cu" signal "IN5")
		(30 "In14.Cu" signal "GND6")
		(32 "In15.Cu" signal "IN6")
		(34 "In16.Cu" signal "GND7")
		(2 "B.Cu" signal "BOTTOM")
		(9 "F.Adhes" user "F.Adhesive")
		(11 "B.Adhes" user "B.Adhesive")
		(13 "F.Paste" user "Package Geometry/Pastemask Top")
		(15 "B.Paste" user "Package Geometry/Pastemask Bottom")
		(5 "F.SilkS" user "Ref Des/Silkscreen Top")
		(7 "B.SilkS" user "Ref Des/Silkscreen Bottom")
		(1 "F.Mask" user "Board Geometry/Soldermask Top")
		(3 "B.Mask" user "Board Geometry/Soldermask Bottom")
		(17 "Dwgs.User" user "User.Drawings")
		(19 "Cmts.User" user "User.Comments")
		(21 "Eco1.User" user "User.Eco1")
		(23 "Eco2.User" user "User.Eco2")
		(25 "Edge.Cuts" user "Board Geometry/Outline")
		(27 "Margin" user)
		(31 "F.CrtYd" user "Package Geometry/Place Bound Top")
		(29 "B.CrtYd" user "Package Geometry/Place Bound Bottom")
		(35 "F.Fab" user "Ref Des/Assembly Top")
		(33 "B.Fab" user "Ref Des/Assembly Bottom")
	)
	(footprint ""
		(layer "F.Cu")
		(at 164.247576 -36.825428)
		(property "Reference" "R4464"
			(at 0 0 0)
			(layer "F.SilkS")
			(hide yes)
			(effects
				(font
					(size 1.27 1.27)
				)
			)
		)
		(property "Value" ""
			(at 0 0 0)
			(layer "F.Fab")
			(effects
				(font
					(size 1.27 1.27)
				)
			)
		)
		(duplicate_pad_numbers_are_jumpers no)
		(fp_line
			(start -0.7874 -0.4064)
			(end 0.7874 -0.4064)
			(stroke
				(width 0.1524)
				(type default)
			)
			(layer "F.SilkS")
		)
		(fp_line
			(start -0.7874 0.4064)
			(end -0.7874 -0.4064)
			(stroke
				(width 0.1524)
				(type default)
			)
			(layer "F.SilkS")
		)
		(fp_line
			(start 0.7874 -0.4064)
			(end 0.7874 0.4064)
			(stroke
				(width 0.1524)
				(type default)
			)
			(layer "F.SilkS")
		)
		(fp_line
			(start 0.7874 0.4064)
			(end -0.7874 0.4064)
			(stroke
				(width 0.1524)
				(type default)
			)
			(layer "F.SilkS")
		)
		(fp_line
			(start -0.67945 -0.305054)
			(end -0.12065 -0.305054)
			(stroke
				(width 0.1)
				(type default)
			)
			(layer "F.Fab")
		)
		(fp_line
			(start -0.67945 0.3048)
			(end -0.67945 -0.305054)
			(stroke
				(width 0.1)
				(type default)
			)
			(layer "F.Fab")
		)
		(fp_line
			(start -0.12065 -0.305054)
			(end -0.12065 -0.2794)
			(stroke
				(width 0.1)
				(type default)
			)
			(layer "F.Fab")
		)
		(fp_line
			(start -0.12065 -0.2794)
			(end 0.12065 -0.2794)
			(stroke
				(width 0.1)
				(type default)
			)
			(layer "F.Fab")
		)
		(fp_line
			(start -0.12065 0.2794)
			(end -0.12065 0.3048)
			(stroke
				(width 0.1)
				(type default)
			)
			(layer "F.Fab")
		)
		(fp_line
			(start -0.12065 0.3048)
			(end -0.67945 0.3048)
			(stroke
				(width 0.1)
				(type default)
			)
			(layer "F.Fab")
		)
		(fp_line
			(start 0.120396 0.2794)
			(end -0.12065 0.2794)
			(stroke
				(width 0.1)
				(type default)
			)
			(layer "F.Fab")
		)
		(fp_line
			(start 0.120396 0.3048)
			(end 0.120396 0.2794)
			(stroke
				(width 0.1)
				(type default)
			)
			(layer "F.Fab")
		)
		(fp_line
			(start 0.12065 -0.3048)
			(end 0.67945 -0.3048)
			(stroke
				(width 0.1)
				(type default)
			)
			(layer "F.Fab")
		)
		(fp_line
			(start 0.12065 -0.2794)
			(end 0.12065 -0.3048)
			(stroke
				(width 0.1)
				(type default)
			)
			(layer "F.Fab")
		)
		(fp_line
			(start 0.67945 -0.3048)
			(end 0.67945 0.3048)
			(stroke
				(width 0.1)
				(type default)
			)
			(layer "F.Fab")
		)
		(fp_line
			(start 0.67945 0.3048)
			(end 0.120396 0.3048)
			(stroke
				(width 0.1)
				(type default)
			)
			(layer "F.Fab")
		)
		(pad "1" smd circle
			(at -0.40005 0)
			(size 0 0)
			(layers "F.Cu" "F.Mask" "F.Paste")
			(net "USB_HUB_2_PGANG")
		)
		(pad "2" smd circle
			(at 0.40005 0)
			(size 0 0)
			(layers "F.Cu" "F.Mask" "F.Paste")
			(net "GND")
		)
	)
	(footprint ""
		(layer "F.Cu")
		(at 352.301048 -247.715024 90)
		(property "Reference" "C405"
			(at 0 0 90)
			(layer "F.SilkS")
			(hide yes)
			(effects
				(font
					(size 1.27 1.27)
				)
			)
		)
		(property "Value" ""
			(at 0 0 90)
			(layer "F.Fab")
			(effects
				(font
					(size 1.27 1.27)
				)
			)
		)
		(duplicate_pad_numbers_are_jumpers no)
		(fp_line
			(start 0.7874 -0.4064)
			(end 0.7874 0.4064)
			(stroke
				(width 0.1524)
				(type default)
			)
			(layer "F.SilkS")
		)
		(fp_line
			(start -0.7874 -0.4064)
			(end 0.7874 -0.4064)
			(stroke
				(width 0.1524)
				(type default)
			)
			(layer "F.SilkS")
		)
		(fp_line
			(start 0.7874 0.4064)
			(end -0.7874 0.4064)
			(stroke
				(width 0.1524)
				(type default)
			)
			(layer "F.SilkS")
		)
		(fp_line
			(start -0.7874 0.4064)
			(end -0.7874 -0.4064)
			(stroke
				(width 0.1524)
				(type default)
			)
			(layer "F.SilkS")
		)
		(fp_line
			(start -0.12065 -0.305054)
			(end -0.12065 -0.2794)
			(stroke
				(width 0.1)
				(type default)
			)
			(layer "F.Fab")
		)
		(fp_line
			(start -0.67945 -0.305054)
			(end -0.12065 -0.305054)
			(stroke
				(width 0.1)
				(type default)
			)
			(layer "F.Fab")
		)
		(fp_line
			(start 0.67945 -0.3048)
			(end 0.67945 0.3048)
			(stroke
				(width 0.1)
				(type default)
			)
			(layer "F.Fab")
		)
		(fp_line
			(start 0.12065 -0.3048)
			(end 0.67945 -0.3048)
			(stroke
				(width 0.1)
				(type default)
			)
			(layer "F.Fab")
		)
		(fp_line
			(start 0.12065 -0.2794)
			(end 0.12065 -0.3048)
			(stroke
				(width 0.1)
				(type default)
			)
			(layer "F.Fab")
		)
		(fp_line
			(start -0.12065 -0.2794)
			(end 0.12065 -0.2794)
			(stroke
				(width 0.1)
				(type default)
			)
			(layer "F.Fab")
		)
		(fp_line
			(start 0.120396 0.2794)
			(end -0.12065 0.2794)
			(stroke
				(width 0.1)
				(type default)
			)
			(layer "F.Fab")
		)
		(fp_line
			(start -0.12065 0.2794)
			(end -0.12065 0.3048)
			(stroke
				(width 0.1)
				(type default)
			)
			(layer "F.Fab")
		)
		(fp_line
			(start 0.67945 0.3048)
			(end 0.120396 0.3048)
			(stroke
				(width 0.1)
				(type default)
			)
			(layer "F.Fab")
		)
		(fp_line
			(start 0.120396 0.3048)
			(end 0.120396 0.2794)
			(stroke
				(width 0.1)
				(type default)
			)
			(layer "F.Fab")
		)
		(fp_line
			(start -0.12065 0.3048)
			(end -0.67945 0.3048)
			(stroke
				(width 0.1)
				(type default)
			)
			(layer "F.Fab")
		)
		(fp_line
			(start -0.67945 0.3048)
			(end -0.67945 -0.305054)
			(stroke
				(width 0.1)
				(type default)
			)
			(layer "F.Fab")
		)
		(pad "1" smd circle
			(at -0.40005 0 90)
			(size 0 0)
			(layers "F.Cu" "F.Mask" "F.Paste")
			(net "PVCCD_HV_CPU0")
		)
		(pad "2" smd circle
			(at 0.40005 0 90)
			(size 0 0)
			(layers "F.Cu" "F.Mask" "F.Paste")
			(net "GND")
		)
	)
)
